(kicad_pcb
	(version 20260206)
	(generator "pcbnew")
	(generator_version "10.0")
	(general
		(thickness 1.6)
		(legacy_teardrops no)
	)
	(paper "A4")
	(title_block
		(title "03242023_DA0F0TMBIJ0_F0T_Motherboard_J_brd_V01_OCP.brd")
		(comment 1 "Grand Teton / footprints 1355-1358 of 6105")
	)
	(layers
		(0 "F.Cu" signal "TOP")
		(4 "In1.Cu" signal "GND")
		(6 "In2.Cu" signal "IN1")
		(8 "In3.Cu" signal "GND1")
		(10 "In4.Cu" signal "IN2")
		(12 "In5.Cu" signal "GND2")
		(14 "In6.Cu" signal "IN3")
		(16 "In7.Cu" signal "GND3")
		(18 "In8.Cu" signal "VCC")
		(20 "In9.Cu" signal "VCC1")
		(22 "In10.Cu" signal "GND4")
		(24 "In11.Cu" signal "IN4")
		(26 "In12.Cu" signal "GND5")
		(28 "In13.Cu" signal "IN5")
		(30 "In14.Cu" signal "GND6")
		(32 "In15.Cu" signal "IN6")
		(34 "In16.Cu" signal "GND7")
		(2 "B.Cu" signal "BOTTOM")
		(9 "F.Adhes" user "F.Adhesive")
		(11 "B.Adhes" user "B.Adhesive")
		(13 "F.Paste" user "Package Geometry/Pastemask Top")
		(15 "B.Paste" user "Package Geometry/Pastemask Bottom")
		(5 "F.SilkS" user "Ref Des/Silkscreen Top")
		(7 "B.SilkS" user "Ref Des/Silkscreen Bottom")
		(1 "F.Mask" user "Board Geometry/Soldermask Top")
		(3 "B.Mask" user "Board Geometry/Soldermask Bottom")
		(17 "Dwgs.User" user "User.Drawings")
		(19 "Cmts.User" user "User.Comments")
		(21 "Eco1.User" user "User.Eco1")
		(23 "Eco2.User" user "User.Eco2")
		(25 "Edge.Cuts" user "Board Geometry/Outline")
		(27 "Margin" user)
		(31 "F.CrtYd" user "Package Geometry/Place Bound Top")
		(29 "B.CrtYd" user "Package Geometry/Place Bound Bottom")
		(35 "F.Fab" user "Ref Des/Assembly Top")
		(33 "B.Fab" user "Ref Des/Assembly Bottom")
	)
	(footprint ""
		(layer "F.Cu")
		(at 83.566508 -74.901552 -90)
		(property "Reference" "R3086"
			(at 0 0 270)
			(layer "F.SilkS")
			(hide yes)
			(effects
				(font
					(size 1.27 1.27)
				)
			)
		)
		(property "Value" ""
			(at 0 0 270)
			(layer "F.Fab")
			(effects
				(font
					(size 1.27 1.27)
				)
			)
		)
		(duplicate_pad_numbers_are_jumpers no)
		(fp_line
			(start -0.7874 0.4064)
			(end -0.7874 -0.4064)
			(stroke
				(width 0.1524)
				(type default)
			)
			(layer "F.SilkS")
		)
		(fp_line
			(start 0.7874 0.4064)
			(end -0.7874 0.4064)
			(stroke
				(width 0.1524)
				(type default)
			)
			(layer "F.SilkS")
		)
		(fp_line
			(start -0.7874 -0.4064)
			(end 0.7874 -0.4064)
			(stroke
				(width 0.1524)
				(type default)
			)
			(layer "F.SilkS")
		)
		(fp_line
			(start 0.7874 -0.4064)
			(end 0.7874 0.4064)
			(stroke
				(width 0.1524)
				(type default)
			)
			(layer "F.SilkS")
		)
		(fp_line
			(start -0.67945 0.3048)
			(end -0.67945 -0.305054)
			(stroke
				(width 0.1)
				(type default)
			)
			(layer "F.Fab")
		)
		(fp_line
			(start -0.12065 0.3048)
			(end -0.67945 0.3048)
			(stroke
				(width 0.1)
				(type default)
			)
			(layer "F.Fab")
		)
		(fp_line
			(start 0.120396 0.3048)
			(end 0.120396 0.2794)
			(stroke
				(width 0.1)
				(type default)
			)
			(layer "F.Fab")
		)
		(fp_line
			(start 0.67945 0.3048)
			(end 0.120396 0.3048)
			(stroke
				(width 0.1)
				(type default)
			)
			(layer "F.Fab")
		)
		(fp_line
			(start -0.12065 0.2794)
			(end -0.12065 0.3048)
			(stroke
				(width 0.1)
				(type default)
			)
			(layer "F.Fab")
		)
		(fp_line
			(start 0.120396 0.2794)
			(end -0.12065 0.2794)
			(stroke
				(width 0.1)
				(type default)
			)
			(layer "F.Fab")
		)
		(fp_line
			(start -0.12065 -0.2794)
			(end 0.12065 -0.2794)
			(stroke
				(width 0.1)
				(type default)
			)
			(layer "F.Fab")
		)
		(fp_line
			(start 0.12065 -0.2794)
			(end 0.12065 -0.3048)
			(stroke
				(width 0.1)
				(type default)
			)
			(layer "F.Fab")
		)
		(fp_line
			(start 0.12065 -0.3048)
			(end 0.67945 -0.3048)
			(stroke
				(width 0.1)
				(type default)
			)
			(layer "F.Fab")
		)
		(fp_line
			(start 0.67945 -0.3048)
			(end 0.67945 0.3048)
			(stroke
				(width 0.1)
				(type default)
			)
			(layer "F.Fab")
		)
		(fp_line
			(start -0.67945 -0.305054)
			(end -0.12065 -0.305054)
			(stroke
				(width 0.1)
				(type default)
			)
			(layer "F.Fab")
		)
		(fp_line
			(start -0.12065 -0.305054)
			(end -0.12065 -0.2794)
			(stroke
				(width 0.1)
				(type default)
			)
			(layer "F.Fab")
		)
		(pad "1" smd circle
			(at -0.40005 0 270)
			(size 0 0)
			(layers "F.Cu" "F.Mask" "F.Paste")
			(net "LED_PWRGD_PVCCD_HV_CPU0")
		)
		(pad "2" smd circle
			(at 0.40005 0 270)
			(size 0 0)
			(layers "F.Cu" "F.Mask" "F.Paste")
			(net "P3V3_AUX")
		)
	)
	(footprint ""
		(layer "F.Cu")
		(at 194.35064 -71.836788 90)
		(property "Reference" "PC2200"
			(at 0 0 90)
			(layer "F.SilkS")
			(hide yes)
			(effects
				(font
					(size 1.27 1.27)
				)
			)
		)
		(property "Value" ""
			(at 0 0 90)
			(layer "F.Fab")
			(effects
				(font
					(size 1.27 1.27)
				)
			)
		)
		(duplicate_pad_numbers_are_jumpers no)
		(fp_line
			(start 0.7874 -0.4064)
			(end 0.7874 0.4064)
			(stroke
				(width 0.1524)
				(type default)
			)
			(layer "F.SilkS")
		)
		(fp_line
			(start -0.7874 -0.4064)
			(end 0.7874 -0.4064)
			(stroke
				(width 0.1524)
				(type default)
			)
			(layer "F.SilkS")
		)
		(fp_line
			(start 0.7874 0.4064)
			(end -0.7874 0.4064)
			(stroke
				(width 0.1524)
				(type default)
			)
			(layer "F.SilkS")
		)
		(fp_line
			(start -0.7874 0.4064)
			(end -0.7874 -0.4064)
			(stroke
				(width 0.1524)
				(type default)
			)
			(layer "F.SilkS")
		)
		(fp_line
			(start -0.12065 -0.305054)
			(end -0.12065 -0.2794)
			(stroke
				(width 0.1)
				(type default)
			)
			(layer "F.Fab")
		)
		(fp_line
			(start -0.67945 -0.305054)
			(end -0.12065 -0.305054)
			(stroke
				(width 0.1)
				(type default)
			)
			(layer "F.Fab")
		)
		(fp_line
			(start 0.67945 -0.3048)
			(end 0.67945 0.3048)
			(stroke
				(width 0.1)
				(type default)
			)
			(layer "F.Fab")
		)
		(fp_line
			(start 0.12065 -0.3048)
			(end 0.67945 -0.3048)
			(stroke
				(width 0.1)
				(type default)
			)
			(layer "F.Fab")
		)
		(fp_line
			(start 0.12065 -0.2794)
			(end 0.12065 -0.3048)
			(stroke
				(width 0.1)
				(type default)
			)
			(layer "F.Fab")
		)
		(fp_line
			(start -0.12065 -0.2794)
			(end 0.12065 -0.2794)
			(stroke
				(width 0.1)
				(type default)
			)
			(layer "F.Fab")
		)
		(fp_line
			(start 0.120396 0.2794)
			(end -0.12065 0.2794)
			(stroke
				(width 0.1)
				(type default)
			)
			(layer "F.Fab")
		)
		(fp_line
			(start -0.12065 0.2794)
			(end -0.12065 0.3048)
			(stroke
				(width 0.1)
				(type default)
			)
			(layer "F.Fab")
		)
		(fp_line
			(start 0.67945 0.3048)
			(end 0.120396 0.3048)
			(stroke
				(width 0.1)
				(type default)
			)
			(layer "F.Fab")
		)
		(fp_line
			(start 0.120396 0.3048)
			(end 0.120396 0.2794)
			(stroke
				(width 0.1)
				(type default)
			)
			(layer "F.Fab")
		)
		(fp_line
			(start -0.12065 0.3048)
			(end -0.67945 0.3048)
			(stroke
				(width 0.1)
				(type default)
			)
			(layer "F.Fab")
		)
		(fp_line
			(start -0.67945 0.3048)
			(end -0.67945 -0.305054)
			(stroke
				(width 0.1)
				(type default)
			)
			(layer "F.Fab")
		)
		(pad "1" smd circle
			(at -0.40005 0 90)
			(size 0 0)
			(layers "F.Cu" "F.Mask" "F.Paste")
			(net "P3V3_AUX")
		)
		(pad "2" smd circle
			(at 0.40005 0 90)
			(size 0 0)
			(layers "F.Cu" "F.Mask" "F.Paste")
			(net "GND")
		)
	)
	(footprint ""
		(layer "F.Cu")
		(at 172.024294 -353.554284)
		(property "Reference" "PU75_P1_1"
			(at -2.245614 -6.277356 0)
			(unlocked yes)
			(layer "F.SilkS")
			(effects
				(font
					(size 0.7874 0.5842)
					(thickness 0.1524)
				)
				(justify left)
			)
		)
		(property "Value" ""
			(at 0 0 0)
			(layer "F.Fab")
			(effects
				(font
					(size 1.27 1.27)
				)
			)
		)
		(duplicate_pad_numbers_are_jumpers no)
		(fp_line
			(start -2.500122 -2.999994)
			(end -2.24409 -2.999994)
			(stroke
				(width 0.1524)
				(type default)
			)
			(layer "F.SilkS")
		)
		(fp_line
			(start -2.500122 -2.529078)
			(end -2.500122 -2.999994)
			(stroke
				(width 0.1524)
				(type default)
			)
			(layer "F.SilkS")
		)
		(fp_line
			(start -2.500122 0.6604)
			(end -2.500122 0.229108)
			(stroke
				(width 0.1524)
				(type default)
			)
			(layer "F.SilkS")
		)
		(fp_line
			(start -2.500122 2.999994)
			(end -2.500122 2.339594)
			(stroke
				(width 0.1524)
				(type default)
			)
			(layer "F.SilkS")
		)
		(fp_line
			(start -2.2987 2.999994)
			(end -2.500122 2.999994)
			(stroke
				(width 0.1524)
				(type default)
			)
			(layer "F.SilkS")
		)
		(fp_line
			(start 2.31394 -2.999994)
			(end 2.500122 -2.999994)
			(stroke
				(width 0.1524)
				(type default)
			)
			(layer "F.SilkS")
		)
		(fp_line
			(start 2.500122 -2.999994)
			(end 2.500122 -2.44348)
			(stroke
				(width 0.1524)
				(type default)
			)
			(layer "F.SilkS")
		)
		(fp_line
			(start 2.500122 2.339594)
			(end 2.500122 2.999994)
			(stroke
				(width 0.1524)
				(type default)
			)
			(layer "F.SilkS")
		)
		(fp_line
			(start 2.500122 2.999994)
			(end 2.2987 2.999994)
			(stroke
				(width 0.1524)
				(type default)
			)
			(layer "F.SilkS")
		)
		(fp_poly
			(pts
				(xy -5.275072 -2.780538) (xy -4.259072 -2.272538) (xy -5.275072 -1.764538)
			)
			(stroke
				(width 0)
				(type default)
			)
			(fill yes)
			(layer "F.SilkS")
		)
		(fp_line
			(start -2.500122 -2.999994)
			(end 2.500122 -2.999994)
			(stroke
				(width 0.1)
				(type default)
			)
			(layer "F.Fab")
		)
		(fp_line
			(start -2.500122 2.999994)
			(end -2.500122 -2.999994)
			(stroke
				(width 0.1)
				(type default)
			)
			(layer "F.Fab")
		)
		(fp_line
			(start 2.500122 -2.999994)
			(end 2.500122 2.999994)
			(stroke
				(width 0.1)
				(type default)
			)
			(layer "F.Fab")
		)
		(fp_line
			(start 2.500122 2.999994)
			(end -2.500122 2.999994)
			(stroke
				(width 0.1)
				(type default)
			)
			(layer "F.Fab")
		)
		(fp_poly
			(pts
				(xy -4.218432 -2.783078) (xy -4.218432 -1.767078) (xy -3.202432 -2.275078)
			)
			(stroke
				(width 0)
				(type default)
			)
			(fill yes)
			(layer "F.Fab")
		)
		(pad "1" smd rect
			(at -2.400046 -2.275078 90)
			(size 0.2286 0.6096)
			(layers "F.Cu" "F.Mask" "F.Paste")
			(net "PVCCFA_EHV_FIVRA_CPU1_VOS1")
		)
		(pad "2" smd rect
			(at -2.400046 -1.82499 90)
			(size 0.2286 0.6096)
			(layers "F.Cu" "F.Mask" "F.Paste")
			(net "GND")
		)
		(pad "3" smd rect
			(at -2.400046 -1.374902 90)
			(size 0.2286 0.6096)
			(layers "F.Cu" "F.Mask" "F.Paste")
			(net "PVCCFA_EHV_FIVRA_CPU1_VDD1")
		)
		(pad "4" smd rect
			(at -2.400046 -0.925068 90)
			(size 0.2286 0.6096)
			(layers "F.Cu" "F.Mask" "F.Paste")
			(net "PVCCFA_EHV_FIVRA_CPU1_PVCC1")
		)
		(pad "5" smd rect
			(at -2.400046 -0.47498 90)
			(size 0.2286 0.6096)
			(layers "F.Cu" "F.Mask" "F.Paste")
			(net "GND")
		)
		(pad "6" smd rect
			(at -2.400046 -0.024892 90)
			(size 0.2286 0.6096)
			(layers "F.Cu" "F.Mask" "F.Paste")
			(net "Net_8505")
		)
		(pad "7_9-20_24" smd circle
			(at 0 1.150112 90)
			(size 0 0)
			(layers "F.Cu" "F.Mask" "F.Paste")
			(net "GND")
		)
		(pad "10_19" smd rect
			(at 0 2.899918 90)
			(size 0.6096 4.318)
			(layers "F.Cu" "F.Mask" "F.Paste")
			(net "SW_PVCCFA_EHV_FIVRA_CPU1_SW1")
		)
		(pad "25_29" smd rect
			(at 1.549908 -1.279906 270)
			(size 2.0574 2.3114)
			(layers "F.Cu" "F.Mask" "F.Paste")
			(net "SW_P12V_PVCCFA_EHV_FIVRA_CPU1_R")
		)
		(pad "30" smd rect
			(at 2.05994 -2.899918)
			(size 0.2286 0.6096)
			(layers "F.Cu" "F.Mask" "F.Paste")
			(net "SW_P12V_PVCCFA_EHV_FIVRA_CPU1_R")
		)
		(pad "31" smd rect
			(at 1.610106 -2.899918)
			(size 0.2286 0.6096)
			(layers "F.Cu" "F.Mask" "F.Paste")
			(net "Net_8506")
		)
		(pad "32" smd rect
			(at 1.160018 -2.899918)
			(size 0.2286 0.6096)
			(layers "F.Cu" "F.Mask" "F.Paste")
			(net "SW_PVCCFA_EHV_FIVRA_CPU1_BOOTR1")
		)
		(pad "33" smd rect
			(at 0.70993 -2.899918)
			(size 0.2286 0.6096)
			(layers "F.Cu" "F.Mask" "F.Paste")
			(net "SW_PVCCFA_EHV_FIVRA_CPU1_BOOT1")
		)
		(pad "34" smd rect
			(at 0.260096 -2.899918)
			(size 0.2286 0.6096)
			(layers "F.Cu" "F.Mask" "F.Paste")
			(net "PVCCFA_EHV_FIVRA_CPU1_PWM1")
		)
		(pad "35" smd rect
			(at -0.189992 -2.899918)
			(size 0.2286 0.6096)
			(layers "F.Cu" "F.Mask" "F.Paste")
			(net "PVCCFA_EHV_FIVRA_CPU1_VDD1")
		)
		(pad "36" smd rect
			(at -0.64008 -2.899918)
			(size 0.2286 0.6096)
			(layers "F.Cu" "F.Mask" "F.Paste")
			(net "PVCCFA_EHV_FIVRA_CPU1_BTSEN")
		)
		(pad "37" smd rect
			(at -1.089914 -2.899918)
			(size 0.2286 0.6096)
			(layers "F.Cu" "F.Mask" "F.Paste")
			(net "PVCCFA_EHV_FIVRA_CPU1_LSET1")
		)
		(pad "38" smd rect
			(at -1.540002 -2.899918)
			(size 0.2286 0.6096)
			(layers "F.Cu" "F.Mask" "F.Paste")
			(net "PVCCFA_EHV_FIVRA_CPU1_IMON1")
		)
		(pad "39" smd rect
			(at -1.99009 -2.899918)
			(size 0.2286 0.6096)
			(layers "F.Cu" "F.Mask" "F.Paste")
			(net "PVCCIN_CPU1_VREF")
		)
		(pad "40" smd rect
			(at -0.87503 -1.27508)
			(size 1.7526 1.9558)
			(layers "F.Cu" "F.Mask" "F.Paste")
			(net "GND")
		)
		(pad "41" smd rect
			(at -1.525016 0.249936 270)
			(size 0.3048 0.4572)
			(layers "F.Cu" "F.Mask" "F.Paste")
			(net "Net_8504")
		)
		(zone
			(layer "F.Cu")
			(hatch none 0.5)
			(connect_pads
				(clearance 0)
			)
			(min_thickness 0.25)
			(keepout
				(tracks not_allowed)
				(vias allowed)
				(pads allowed)
				(copperpour not_allowed)
				(footprints allowed)
			)
			(placement
				(enabled no)
				(sheetname "")
			)
			(fill
				(thermal_gap 0.5)
				(thermal_bridge_width 0.5)
				(island_removal_mode 0)
			)
			(polygon
				(pts
					(xy 169.524172 -350.55429) (xy 169.524172 -351.285048) (xy 174.524416 -351.285048) (xy 174.524416 -350.55429)
					(xy 174.234094 -350.55429) (xy 174.234094 -351.009966) (xy 169.814494 -351.009966) (xy 169.814494 -350.55429)
				)
			)
		)
		(zone
			(layer "F.Cu")
			(hatch none 0.5)
			(connect_pads
				(clearance 0)
			)
			(min_thickness 0.25)
			(keepout
				(tracks not_allowed)
				(vias allowed)
				(pads allowed)
				(copperpour not_allowed)
				(footprints allowed)
			)
			(placement
				(enabled no)
				(sheetname "")
			)
			(fill
				(thermal_gap 0.5)
				(thermal_bridge_width 0.5)
				(island_removal_mode 0)
			)
			(polygon
				(pts
					(xy 170.26636 -353.800664) (xy 171.03344 -353.800664) (xy 171.03344 -353.471988) (xy 171.073572 -353.471988)
					(xy 171.073572 -352.859848) (xy 171.018708 -352.804984) (xy 169.524172 -352.804984) (xy 169.524172 -353.261676)
					(xy 170.219878 -353.261676) (xy 170.219878 -353.101148) (xy 170.778678 -353.101148) (xy 170.778678 -353.507548)
					(xy 170.219878 -353.507548) (xy 170.219878 -353.287076) (xy 169.524172 -353.287076) (xy 169.524172 -353.414076)
					(xy 169.979848 -353.414076) (xy 169.979848 -353.786948) (xy 170.26636 -353.786948)
				)
			)
		)
	)
	(footprint ""
		(layer "F.Cu")
		(at 80.384396 -57.977532 180)
		(property "Reference" "PR3829"
			(at 0 0 180)
			(layer "F.SilkS")
			(hide yes)
			(effects
				(font
					(size 1.27 1.27)
				)
			)
		)
		(property "Value" ""
			(at 0 0 180)
			(layer "F.Fab")
			(effects
				(font
					(size 1.27 1.27)
				)
			)
		)
		(duplicate_pad_numbers_are_jumpers no)
		(fp_line
			(start 0.7874 0.4064)
			(end -0.7874 0.4064)
			(stroke
				(width 0.1524)
				(type default)
			)
			(layer "F.SilkS")
		)
		(fp_line
			(start 0.7874 -0.4064)
			(end 0.7874 0.4064)
			(stroke
				(width 0.1524)
				(type default)
			)
			(layer "F.SilkS")
		)
		(fp_line
			(start -0.7874 0.4064)
			(end -0.7874 -0.4064)
			(stroke
				(width 0.1524)
				(type default)
			)
			(layer "F.SilkS")
		)
		(fp_line
			(start -0.7874 -0.4064)
			(end 0.7874 -0.4064)
			(stroke
				(width 0.1524)
				(type default)
			)
			(layer "F.SilkS")
		)
		(fp_line
			(start 0.67945 0.3048)
			(end 0.120396 0.3048)
			(stroke
				(width 0.1)
				(type default)
			)
			(layer "F.Fab")
		)
		(fp_line
			(start 0.67945 -0.3048)
			(end 0.67945 0.3048)
			(stroke
				(width 0.1)
				(type default)
			)
			(layer "F.Fab")
		)
		(fp_line
			(start 0.12065 -0.2794)
			(end 0.12065 -0.3048)
			(stroke
				(width 0.1)
				(type default)
			)
			(layer "F.Fab")
		)
		(fp_line
			(start 0.12065 -0.3048)
			(end 0.67945 -0.3048)
			(stroke
				(width 0.1)
				(type default)
			)
			(layer "F.Fab")
		)
		(fp_line
			(start 0.120396 0.3048)
			(end 0.120396 0.2794)
			(stroke
				(width 0.1)
				(type default)
			)
			(layer "F.Fab")
		)
		(fp_line
			(start 0.120396 0.2794)
			(end -0.12065 0.2794)
			(stroke
				(width 0.1)
				(type default)
			)
			(layer "F.Fab")
		)
		(fp_line
			(start -0.12065 0.3048)
			(end -0.67945 0.3048)
			(stroke
				(width 0.1)
				(type default)
			)
			(layer "F.Fab")
		)
		(fp_line
			(start -0.12065 0.2794)
			(end -0.12065 0.3048)
			(stroke
				(width 0.1)
				(type default)
			)
			(layer "F.Fab")
		)
		(fp_line
			(start -0.12065 -0.2794)
			(end 0.12065 -0.2794)
			(stroke
				(width 0.1)
				(type default)
			)
			(layer "F.Fab")
		)
		(fp_line
			(start -0.12065 -0.305054)
			(end -0.12065 -0.2794)
			(stroke
				(width 0.1)
				(type default)
			)
			(layer "F.Fab")
		)
		(fp_line
			(start -0.67945 0.3048)
			(end -0.67945 -0.305054)
			(stroke
				(width 0.1)
				(type default)
			)
			(layer "F.Fab")
		)
		(fp_line
			(start -0.67945 -0.305054)
			(end -0.12065 -0.305054)
			(stroke
				(width 0.1)
				(type default)
			)
			(layer "F.Fab")
		)
		(pad "1" smd circle
			(at -0.40005 0 180)
			(size 0 0)
			(layers "F.Cu" "F.Mask" "F.Paste")
			(net "P3V3_OCP_UV_2")
		)
		(pad "2" smd circle
			(at 0.40005 0 180)
			(size 0 0)
			(layers "F.Cu" "F.Mask" "F.Paste")
			(net "P3V3_OCP_OV_2")
		)
	)
)
